(kicad_pcb
	(version 20260206)
	(generator "pcbnew")
	(generator_version "10.0")
	(general
		(thickness 1.6)
		(legacy_teardrops no)
	)
	(paper "A4")
	(title_block
		(title "03242023_DA0F0TMBIJ0_F0T_Motherboard_J_brd_V01_OCP.brd")
		(comment 1 "Grand Teton / footprints 5485-5491 of 6105")
	)
	(layers
		(0 "F.Cu" signal "TOP")
		(4 "In1.Cu" signal "GND")
		(6 "In2.Cu" signal "IN1")
		(8 "In3.Cu" signal "GND1")
		(10 "In4.Cu" signal "IN2")
		(12 "In5.Cu" signal "GND2")
		(14 "In6.Cu" signal "IN3")
		(16 "In7.Cu" signal "GND3")
		(18 "In8.Cu" signal "VCC")
		(20 "In9.Cu" signal "VCC1")
		(22 "In10.Cu" signal "GND4")
		(24 "In11.Cu" signal "IN4")
		(26 "In12.Cu" signal "GND5")
		(28 "In13.Cu" signal "IN5")
		(30 "In14.Cu" signal "GND6")
		(32 "In15.Cu" signal "IN6")
		(34 "In16.Cu" signal "GND7")
		(2 "B.Cu" signal "BOTTOM")
		(9 "F.Adhes" user "F.Adhesive")
		(11 "B.Adhes" user "B.Adhesive")
		(13 "F.Paste" user "Package Geometry/Pastemask Top")
		(15 "B.Paste" user "Package Geometry/Pastemask Bottom")
		(5 "F.SilkS" user "Ref Des/Silkscreen Top")
		(7 "B.SilkS" user "Ref Des/Silkscreen Bottom")
		(1 "F.Mask" user "Board Geometry/Soldermask Top")
		(3 "B.Mask" user "Board Geometry/Soldermask Bottom")
		(17 "Dwgs.User" user "User.Drawings")
		(19 "Cmts.User" user "User.Comments")
		(21 "Eco1.User" user "User.Eco1")
		(23 "Eco2.User" user "User.Eco2")
		(25 "Edge.Cuts" user "Board Geometry/Outline")
		(27 "Margin" user)
		(31 "F.CrtYd" user "Package Geometry/Place Bound Top")
		(29 "B.CrtYd" user "Package Geometry/Place Bound Bottom")
		(35 "F.Fab" user "Ref Des/Assembly Top")
		(33 "B.Fab" user "Ref Des/Assembly Bottom")
	)
	(footprint ""
		(layer "B.Cu")
		(at 350.319848 -54.435756 90)
		(property "Reference" "C1273"
			(at 0 0 90)
			(layer "B.SilkS")
			(hide yes)
			(effects
				(font
					(size 1.27 1.27)
				)
				(justify mirror)
			)
		)
		(property "Value" ""
			(at 0 0 90)
			(layer "B.Fab")
			(effects
				(font
					(size 1.27 1.27)
				)
				(justify mirror)
			)
		)
		(duplicate_pad_numbers_are_jumpers no)
		(fp_line
			(start 1.524 -0.762)
			(end -1.524 -0.762)
			(stroke
				(width 0.1524)
				(type default)
			)
			(layer "B.SilkS")
		)
		(fp_line
			(start -1.524 -0.762)
			(end -1.524 0.762)
			(stroke
				(width 0.1524)
				(type default)
			)
			(layer "B.SilkS")
		)
		(fp_line
			(start 1.524 0.762)
			(end 1.524 -0.762)
			(stroke
				(width 0.1524)
				(type default)
			)
			(layer "B.SilkS")
		)
		(fp_line
			(start -1.524 0.762)
			(end 1.524 0.762)
			(stroke
				(width 0.1524)
				(type default)
			)
			(layer "B.SilkS")
		)
		(fp_line
			(start 1.1049 -0.724916)
			(end 1.1049 0.724916)
			(stroke
				(width 0.1)
				(type default)
			)
			(layer "B.Fab")
		)
		(fp_line
			(start -1.1049 -0.724916)
			(end 1.1049 -0.724916)
			(stroke
				(width 0.1)
				(type default)
			)
			(layer "B.Fab")
		)
		(fp_line
			(start 1.1049 0.724916)
			(end -1.1049 0.724916)
			(stroke
				(width 0.1)
				(type default)
			)
			(layer "B.Fab")
		)
		(fp_line
			(start -1.1049 0.724916)
			(end -1.1049 -0.724916)
			(stroke
				(width 0.1)
				(type default)
			)
			(layer "B.Fab")
		)
		(pad "1" smd rect
			(at 0.889 0 90)
			(size 1.016 1.27)
			(layers "B.Cu" "B.Mask" "B.Paste")
			(net "P1V8_PCH_PLL_AUX")
		)
		(pad "2" smd rect
			(at -0.889 0 90)
			(size 1.016 1.27)
			(layers "B.Cu" "B.Mask" "B.Paste")
			(net "GND")
		)
	)
	(footprint ""
		(layer "B.Cu")
		(at 66.150744 -14.26464)
		(property "Reference" "C1839"
			(at 0 0 0)
			(layer "B.SilkS")
			(hide yes)
			(effects
				(font
					(size 1.27 1.27)
				)
				(justify mirror)
			)
		)
		(property "Value" ""
			(at 0 0 0)
			(layer "B.Fab")
			(effects
				(font
					(size 1.27 1.27)
				)
				(justify mirror)
			)
		)
		(duplicate_pad_numbers_are_jumpers no)
		(fp_line
			(start -0.7874 -0.4064)
			(end -0.7874 0.4064)
			(stroke
				(width 0.1524)
				(type default)
			)
			(layer "B.SilkS")
		)
		(fp_line
			(start -0.7874 0.4064)
			(end 0.7874 0.4064)
			(stroke
				(width 0.1524)
				(type default)
			)
			(layer "B.SilkS")
		)
		(fp_line
			(start 0.7874 -0.4064)
			(end -0.7874 -0.4064)
			(stroke
				(width 0.1524)
				(type default)
			)
			(layer "B.SilkS")
		)
		(fp_line
			(start 0.7874 0.4064)
			(end 0.7874 -0.4064)
			(stroke
				(width 0.1524)
				(type default)
			)
			(layer "B.SilkS")
		)
		(fp_line
			(start -0.67945 -0.3048)
			(end -0.67945 0.3048)
			(stroke
				(width 0.1)
				(type default)
			)
			(layer "B.Fab")
		)
		(fp_line
			(start -0.67945 0.3048)
			(end -0.120396 0.3048)
			(stroke
				(width 0.1)
				(type default)
			)
			(layer "B.Fab")
		)
		(fp_line
			(start -0.12065 -0.3048)
			(end -0.67945 -0.3048)
			(stroke
				(width 0.1)
				(type default)
			)
			(layer "B.Fab")
		)
		(fp_line
			(start -0.12065 -0.2794)
			(end -0.12065 -0.3048)
			(stroke
				(width 0.1)
				(type default)
			)
			(layer "B.Fab")
		)
		(fp_line
			(start -0.120396 0.2794)
			(end 0.12065 0.2794)
			(stroke
				(width 0.1)
				(type default)
			)
			(layer "B.Fab")
		)
		(fp_line
			(start -0.120396 0.3048)
			(end -0.120396 0.2794)
			(stroke
				(width 0.1)
				(type default)
			)
			(layer "B.Fab")
		)
		(fp_line
			(start 0.12065 -0.305054)
			(end 0.12065 -0.2794)
			(stroke
				(width 0.1)
				(type default)
			)
			(layer "B.Fab")
		)
		(fp_line
			(start 0.12065 -0.2794)
			(end -0.12065 -0.2794)
			(stroke
				(width 0.1)
				(type default)
			)
			(layer "B.Fab")
		)
		(fp_line
			(start 0.12065 0.2794)
			(end 0.12065 0.3048)
			(stroke
				(width 0.1)
				(type default)
			)
			(layer "B.Fab")
		)
		(fp_line
			(start 0.12065 0.3048)
			(end 0.67945 0.3048)
			(stroke
				(width 0.1)
				(type default)
			)
			(layer "B.Fab")
		)
		(fp_line
			(start 0.67945 -0.305054)
			(end 0.12065 -0.305054)
			(stroke
				(width 0.1)
				(type default)
			)
			(layer "B.Fab")
		)
		(fp_line
			(start 0.67945 0.3048)
			(end 0.67945 -0.305054)
			(stroke
				(width 0.1)
				(type default)
			)
			(layer "B.Fab")
		)
		(pad "1" smd circle
			(at 0.40005 0 180)
			(size 0 0)
			(layers "B.Cu" "B.Mask" "B.Paste")
			(net "P12V_OCP_V3_2")
		)
		(pad "2" smd circle
			(at -0.40005 0 180)
			(size 0 0)
			(layers "B.Cu" "B.Mask" "B.Paste")
			(net "GND")
		)
	)
	(footprint ""
		(layer "B.Cu")
		(at 144.50187 -27.843988 180)
		(property "Reference" "R4465"
			(at 0 0 0)
			(layer "B.SilkS")
			(hide yes)
			(effects
				(font
					(size 1.27 1.27)
				)
				(justify mirror)
			)
		)
		(property "Value" ""
			(at 0 0 0)
			(layer "B.Fab")
			(effects
				(font
					(size 1.27 1.27)
				)
				(justify mirror)
			)
		)
		(duplicate_pad_numbers_are_jumpers no)
		(fp_line
			(start 0.7874 0.4064)
			(end 0.7874 -0.4064)
			(stroke
				(width 0.1524)
				(type default)
			)
			(layer "B.SilkS")
		)
		(fp_line
			(start 0.7874 -0.4064)
			(end -0.7874 -0.4064)
			(stroke
				(width 0.1524)
				(type default)
			)
			(layer "B.SilkS")
		)
		(fp_line
			(start -0.7874 0.4064)
			(end 0.7874 0.4064)
			(stroke
				(width 0.1524)
				(type default)
			)
			(layer "B.SilkS")
		)
		(fp_line
			(start -0.7874 -0.4064)
			(end -0.7874 0.4064)
			(stroke
				(width 0.1524)
				(type default)
			)
			(layer "B.SilkS")
		)
		(fp_line
			(start 0.67945 0.3048)
			(end 0.67945 -0.305054)
			(stroke
				(width 0.1)
				(type default)
			)
			(layer "B.Fab")
		)
		(fp_line
			(start 0.67945 -0.305054)
			(end 0.12065 -0.305054)
			(stroke
				(width 0.1)
				(type default)
			)
			(layer "B.Fab")
		)
		(fp_line
			(start 0.12065 0.3048)
			(end 0.67945 0.3048)
			(stroke
				(width 0.1)
				(type default)
			)
			(layer "B.Fab")
		)
		(fp_line
			(start 0.12065 0.2794)
			(end 0.12065 0.3048)
			(stroke
				(width 0.1)
				(type default)
			)
			(layer "B.Fab")
		)
		(fp_line
			(start 0.12065 -0.2794)
			(end -0.12065 -0.2794)
			(stroke
				(width 0.1)
				(type default)
			)
			(layer "B.Fab")
		)
		(fp_line
			(start 0.12065 -0.305054)
			(end 0.12065 -0.2794)
			(stroke
				(width 0.1)
				(type default)
			)
			(layer "B.Fab")
		)
		(fp_line
			(start -0.120396 0.3048)
			(end -0.120396 0.2794)
			(stroke
				(width 0.1)
				(type default)
			)
			(layer "B.Fab")
		)
		(fp_line
			(start -0.120396 0.2794)
			(end 0.12065 0.2794)
			(stroke
				(width 0.1)
				(type default)
			)
			(layer "B.Fab")
		)
		(fp_line
			(start -0.12065 -0.2794)
			(end -0.12065 -0.3048)
			(stroke
				(width 0.1)
				(type default)
			)
			(layer "B.Fab")
		)
		(fp_line
			(start -0.12065 -0.3048)
			(end -0.67945 -0.3048)
			(stroke
				(width 0.1)
				(type default)
			)
			(layer "B.Fab")
		)
		(fp_line
			(start -0.67945 0.3048)
			(end -0.120396 0.3048)
			(stroke
				(width 0.1)
				(type default)
			)
			(layer "B.Fab")
		)
		(fp_line
			(start -0.67945 -0.3048)
			(end -0.67945 0.3048)
			(stroke
				(width 0.1)
				(type default)
			)
			(layer "B.Fab")
		)
		(pad "1" smd circle
			(at 0.40005 0)
			(size 0 0)
			(layers "B.Cu" "B.Mask" "B.Paste")
			(net "PD_USB_HUB_2_EQ")
		)
		(pad "2" smd circle
			(at -0.40005 0)
			(size 0 0)
			(layers "B.Cu" "B.Mask" "B.Paste")
			(net "GND")
		)
	)
	(footprint ""
		(layer "B.Cu")
		(at 164.64788 -107.025948)
		(property "Reference" "R1853"
			(at 0 0 0)
			(layer "B.SilkS")
			(hide yes)
			(effects
				(font
					(size 1.27 1.27)
				)
				(justify mirror)
			)
		)
		(property "Value" ""
			(at 0 0 0)
			(layer "B.Fab")
			(effects
				(font
					(size 1.27 1.27)
				)
				(justify mirror)
			)
		)
		(duplicate_pad_numbers_are_jumpers no)
		(fp_line
			(start -0.7874 -0.4064)
			(end -0.7874 0.4064)
			(stroke
				(width 0.1524)
				(type default)
			)
			(layer "B.SilkS")
		)
		(fp_line
			(start -0.7874 0.4064)
			(end 0.7874 0.4064)
			(stroke
				(width 0.1524)
				(type default)
			)
			(layer "B.SilkS")
		)
		(fp_line
			(start 0.7874 -0.4064)
			(end -0.7874 -0.4064)
			(stroke
				(width 0.1524)
				(type default)
			)
			(layer "B.SilkS")
		)
		(fp_line
			(start 0.7874 0.4064)
			(end 0.7874 -0.4064)
			(stroke
				(width 0.1524)
				(type default)
			)
			(layer "B.SilkS")
		)
		(fp_line
			(start -0.67945 -0.3048)
			(end -0.67945 0.3048)
			(stroke
				(width 0.1)
				(type default)
			)
			(layer "B.Fab")
		)
		(fp_line
			(start -0.67945 0.3048)
			(end -0.120396 0.3048)
			(stroke
				(width 0.1)
				(type default)
			)
			(layer "B.Fab")
		)
		(fp_line
			(start -0.12065 -0.3048)
			(end -0.67945 -0.3048)
			(stroke
				(width 0.1)
				(type default)
			)
			(layer "B.Fab")
		)
		(fp_line
			(start -0.12065 -0.2794)
			(end -0.12065 -0.3048)
			(stroke
				(width 0.1)
				(type default)
			)
			(layer "B.Fab")
		)
		(fp_line
			(start -0.120396 0.2794)
			(end 0.12065 0.2794)
			(stroke
				(width 0.1)
				(type default)
			)
			(layer "B.Fab")
		)
		(fp_line
			(start -0.120396 0.3048)
			(end -0.120396 0.2794)
			(stroke
				(width 0.1)
				(type default)
			)
			(layer "B.Fab")
		)
		(fp_line
			(start 0.12065 -0.305054)
			(end 0.12065 -0.2794)
			(stroke
				(width 0.1)
				(type default)
			)
			(layer "B.Fab")
		)
		(fp_line
			(start 0.12065 -0.2794)
			(end -0.12065 -0.2794)
			(stroke
				(width 0.1)
				(type default)
			)
			(layer "B.Fab")
		)
		(fp_line
			(start 0.12065 0.2794)
			(end 0.12065 0.3048)
			(stroke
				(width 0.1)
				(type default)
			)
			(layer "B.Fab")
		)
		(fp_line
			(start 0.12065 0.3048)
			(end 0.67945 0.3048)
			(stroke
				(width 0.1)
				(type default)
			)
			(layer "B.Fab")
		)
		(fp_line
			(start 0.67945 -0.305054)
			(end 0.12065 -0.305054)
			(stroke
				(width 0.1)
				(type default)
			)
			(layer "B.Fab")
		)
		(fp_line
			(start 0.67945 0.3048)
			(end 0.67945 -0.305054)
			(stroke
				(width 0.1)
				(type default)
			)
			(layer "B.Fab")
		)
		(pad "1" smd circle
			(at 0.40005 0 180)
			(size 0 0)
			(layers "B.Cu" "B.Mask" "B.Paste")
			(net "VIRTUAL_RESEAT_FPGA_R_N")
		)
		(pad "2" smd circle
			(at -0.40005 0 180)
			(size 0 0)
			(layers "B.Cu" "B.Mask" "B.Paste")
			(net "VIRTUAL_RESEAT_FPGA_N")
		)
	)
	(footprint ""
		(layer "B.Cu")
		(at 368.767868 -324.911466 -90)
		(property "Reference" "PC290_P0_4"
			(at 0 0 90)
			(layer "B.SilkS")
			(hide yes)
			(effects
				(font
					(size 1.27 1.27)
				)
				(justify mirror)
			)
		)
		(property "Value" ""
			(at 0 0 90)
			(layer "B.Fab")
			(effects
				(font
					(size 1.27 1.27)
				)
				(justify mirror)
			)
		)
		(duplicate_pad_numbers_are_jumpers no)
		(fp_line
			(start -1.524 0.762)
			(end 1.524 0.762)
			(stroke
				(width 0.1524)
				(type default)
			)
			(layer "B.SilkS")
		)
		(fp_line
			(start 1.524 0.762)
			(end 1.524 -0.762)
			(stroke
				(width 0.1524)
				(type default)
			)
			(layer "B.SilkS")
		)
		(fp_line
			(start -1.524 -0.762)
			(end -1.524 0.762)
			(stroke
				(width 0.1524)
				(type default)
			)
			(layer "B.SilkS")
		)
		(fp_line
			(start 1.524 -0.762)
			(end -1.524 -0.762)
			(stroke
				(width 0.1524)
				(type default)
			)
			(layer "B.SilkS")
		)
		(fp_line
			(start -1.1049 0.724916)
			(end -1.1049 -0.724916)
			(stroke
				(width 0.1)
				(type default)
			)
			(layer "B.Fab")
		)
		(fp_line
			(start 1.1049 0.724916)
			(end -1.1049 0.724916)
			(stroke
				(width 0.1)
				(type default)
			)
			(layer "B.Fab")
		)
		(fp_line
			(start -1.1049 -0.724916)
			(end 1.1049 -0.724916)
			(stroke
				(width 0.1)
				(type default)
			)
			(layer "B.Fab")
		)
		(fp_line
			(start 1.1049 -0.724916)
			(end 1.1049 0.724916)
			(stroke
				(width 0.1)
				(type default)
			)
			(layer "B.Fab")
		)
		(pad "1" smd rect
			(at 0.889 0 270)
			(size 1.016 1.27)
			(layers "B.Cu" "B.Mask" "B.Paste")
			(net "PVCCIN_CPU0")
		)
		(pad "2" smd rect
			(at -0.889 0 270)
			(size 1.016 1.27)
			(layers "B.Cu" "B.Mask" "B.Paste")
			(net "GND")
		)
	)
	(footprint ""
		(layer "B.Cu")
		(at 358.861868 -334.703166 -90)
		(property "Reference" "PR147"
			(at 0 0 90)
			(layer "B.SilkS")
			(hide yes)
			(effects
				(font
					(size 1.27 1.27)
				)
				(justify mirror)
			)
		)
		(property "Value" ""
			(at 0 0 90)
			(layer "B.Fab")
			(effects
				(font
					(size 1.27 1.27)
				)
				(justify mirror)
			)
		)
		(duplicate_pad_numbers_are_jumpers no)
		(fp_line
			(start -0.7874 0.4064)
			(end 0.7874 0.4064)
			(stroke
				(width 0.1524)
				(type default)
			)
			(layer "B.SilkS")
		)
		(fp_line
			(start 0.7874 0.4064)
			(end 0.7874 -0.4064)
			(stroke
				(width 0.1524)
				(type default)
			)
			(layer "B.SilkS")
		)
		(fp_line
			(start -0.7874 -0.4064)
			(end -0.7874 0.4064)
			(stroke
				(width 0.1524)
				(type default)
			)
			(layer "B.SilkS")
		)
		(fp_line
			(start 0.7874 -0.4064)
			(end -0.7874 -0.4064)
			(stroke
				(width 0.1524)
				(type default)
			)
			(layer "B.SilkS")
		)
		(fp_line
			(start -0.67945 0.3048)
			(end -0.120396 0.3048)
			(stroke
				(width 0.1)
				(type default)
			)
			(layer "B.Fab")
		)
		(fp_line
			(start -0.120396 0.3048)
			(end -0.120396 0.2794)
			(stroke
				(width 0.1)
				(type default)
			)
			(layer "B.Fab")
		)
		(fp_line
			(start 0.12065 0.3048)
			(end 0.67945 0.3048)
			(stroke
				(width 0.1)
				(type default)
			)
			(layer "B.Fab")
		)
		(fp_line
			(start 0.67945 0.3048)
			(end 0.67945 -0.305054)
			(stroke
				(width 0.1)
				(type default)
			)
			(layer "B.Fab")
		)
		(fp_line
			(start -0.120396 0.2794)
			(end 0.12065 0.2794)
			(stroke
				(width 0.1)
				(type default)
			)
			(layer "B.Fab")
		)
		(fp_line
			(start 0.12065 0.2794)
			(end 0.12065 0.3048)
			(stroke
				(width 0.1)
				(type default)
			)
			(layer "B.Fab")
		)
		(fp_line
			(start -0.12065 -0.2794)
			(end -0.12065 -0.3048)
			(stroke
				(width 0.1)
				(type default)
			)
			(layer "B.Fab")
		)
		(fp_line
			(start 0.12065 -0.2794)
			(end -0.12065 -0.2794)
			(stroke
				(width 0.1)
				(type default)
			)
			(layer "B.Fab")
		)
		(fp_line
			(start -0.67945 -0.3048)
			(end -0.67945 0.3048)
			(stroke
				(width 0.1)
				(type default)
			)
			(layer "B.Fab")
		)
		(fp_line
			(start -0.12065 -0.3048)
			(end -0.67945 -0.3048)
			(stroke
				(width 0.1)
				(type default)
			)
			(layer "B.Fab")
		)
		(fp_line
			(start 0.12065 -0.305054)
			(end 0.12065 -0.2794)
			(stroke
				(width 0.1)
				(type default)
			)
			(layer "B.Fab")
		)
		(fp_line
			(start 0.67945 -0.305054)
			(end 0.12065 -0.305054)
			(stroke
				(width 0.1)
				(type default)
			)
			(layer "B.Fab")
		)
		(pad "1" smd circle
			(at 0.40005 0 90)
			(size 0 0)
			(layers "B.Cu" "B.Mask" "B.Paste")
			(net "PVCCIN_CPU0_PVCC")
		)
		(pad "2" smd circle
			(at -0.40005 0 90)
			(size 0 0)
			(layers "B.Cu" "B.Mask" "B.Paste")
			(net "PVCCIN_CPU0_VDD3")
		)
	)
	(footprint ""
		(layer "B.Cu")
		(at 193.38036 -119.344948 180)
		(property "Reference" "R2244"
			(at 0 0 0)
			(layer "B.SilkS")
			(hide yes)
			(effects
				(font
					(size 1.27 1.27)
				)
				(justify mirror)
			)
		)
		(property "Value" ""
			(at 0 0 0)
			(layer "B.Fab")
			(effects
				(font
					(size 1.27 1.27)
				)
				(justify mirror)
			)
		)
		(duplicate_pad_numbers_are_jumpers no)
		(fp_line
			(start 0.7874 0.4064)
			(end 0.7874 -0.4064)
			(stroke
				(width 0.1524)
				(type default)
			)
			(layer "B.SilkS")
		)
		(fp_line
			(start 0.7874 -0.4064)
			(end -0.7874 -0.4064)
			(stroke
				(width 0.1524)
				(type default)
			)
			(layer "B.SilkS")
		)
		(fp_line
			(start -0.7874 0.4064)
			(end 0.7874 0.4064)
			(stroke
				(width 0.1524)
				(type default)
			)
			(layer "B.SilkS")
		)
		(fp_line
			(start -0.7874 -0.4064)
			(end -0.7874 0.4064)
			(stroke
				(width 0.1524)
				(type default)
			)
			(layer "B.SilkS")
		)
		(fp_line
			(start 0.67945 0.3048)
			(end 0.67945 -0.305054)
			(stroke
				(width 0.1)
				(type default)
			)
			(layer "B.Fab")
		)
		(fp_line
			(start 0.67945 -0.305054)
			(end 0.12065 -0.305054)
			(stroke
				(width 0.1)
				(type default)
			)
			(layer "B.Fab")
		)
		(fp_line
			(start 0.12065 0.3048)
			(end 0.67945 0.3048)
			(stroke
				(width 0.1)
				(type default)
			)
			(layer "B.Fab")
		)
		(fp_line
			(start 0.12065 0.2794)
			(end 0.12065 0.3048)
			(stroke
				(width 0.1)
				(type default)
			)
			(layer "B.Fab")
		)
		(fp_line
			(start 0.12065 -0.2794)
			(end -0.12065 -0.2794)
			(stroke
				(width 0.1)
				(type default)
			)
			(layer "B.Fab")
		)
		(fp_line
			(start 0.12065 -0.305054)
			(end 0.12065 -0.2794)
			(stroke
				(width 0.1)
				(type default)
			)
			(layer "B.Fab")
		)
		(fp_line
			(start -0.120396 0.3048)
			(end -0.120396 0.2794)
			(stroke
				(width 0.1)
				(type default)
			)
			(layer "B.Fab")
		)
		(fp_line
			(start -0.120396 0.2794)
			(end 0.12065 0.2794)
			(stroke
				(width 0.1)
				(type default)
			)
			(layer "B.Fab")
		)
		(fp_line
			(start -0.12065 -0.2794)
			(end -0.12065 -0.3048)
			(stroke
				(width 0.1)
				(type default)
			)
			(layer "B.Fab")
		)
		(fp_line
			(start -0.12065 -0.3048)
			(end -0.67945 -0.3048)
			(stroke
				(width 0.1)
				(type default)
			)
			(layer "B.Fab")
		)
		(fp_line
			(start -0.67945 0.3048)
			(end -0.120396 0.3048)
			(stroke
				(width 0.1)
				(type default)
			)
			(layer "B.Fab")
		)
		(fp_line
			(start -0.67945 -0.3048)
			(end -0.67945 0.3048)
			(stroke
				(width 0.1)
				(type default)
			)
			(layer "B.Fab")
		)
		(pad "1" smd circle
			(at 0.40005 0)
			(size 0 0)
			(layers "B.Cu" "B.Mask" "B.Paste")
			(net "ROT_P1_RST_IND_N_R")
		)
		(pad "2" smd circle
			(at -0.40005 0)
			(size 0 0)
			(layers "B.Cu" "B.Mask" "B.Paste")
			(net "P3V3_AUX")
		)
	)
)
